(kicad_pcb
	(version 20241229)
	(generator "pcbnew")
	(generator_version "9.0")
	(general
		(thickness 1.292)
		(legacy_teardrops no)
	)
	(paper "A4")
	(title_block
		(title "LPDDR5 Testbed")
		(date "2023-12-19")
		(rev "1.0.0")
		(comment 9 "footprint 16 of 160 (J1), pads 188-264 of 264")
	)
	(layers
		(0 "F.Cu" signal)
		(4 "In1.Cu" power)
		(6 "In2.Cu" power)
		(8 "In3.Cu" signal)
		(10 "In4.Cu" signal)
		(2 "B.Cu" signal)
		(9 "F.Adhes" user "F.Adhesive")
		(11 "B.Adhes" user "B.Adhesive")
		(13 "F.Paste" user)
		(15 "B.Paste" user)
		(5 "F.SilkS" user "F.Silkscreen")
		(7 "B.SilkS" user "B.Silkscreen")
		(1 "F.Mask" user)
		(3 "B.Mask" user)
		(17 "Dwgs.User" user "User.Drawings")
		(19 "Cmts.User" user "User.Comments")
		(21 "Eco1.User" user "User.Eco1")
		(23 "Eco2.User" user "User.Eco2")
		(25 "Edge.Cuts" user)
		(27 "Margin" user)
		(31 "F.CrtYd" user "F.Courtyard")
		(29 "B.CrtYd" user "B.Courtyard")
		(35 "F.Fab" user)
		(33 "B.Fab" user)
	)
	(footprint "lpddr5-testbed-footprints:Edge_Conn_Bus_DDR5_SODIMM"
		(locked yes)
		(layer "F.Cu")
		(at 99.975 100)
		(descr "SODIMM DDR5 Edge Connector")
		(tags "SODIMM DDR5 Edge Connector")
		(property "Reference" "J1"
			(at 0 -4.2 0)
			(unlocked yes)
			(layer "F.SilkS")
			(effects
				(font
					(size 0.7 0.7)
					(thickness 0.15)
				)
				(justify left bottom)
			)
		)
		(property "Value" "Edge_Conn_Bus_DDR5_SODIMM_1xDetectPin"
			(at 0 1 0)
			(layer "F.Fab")
			(effects
				(font
					(size 0.7 0.7)
					(thickness 0.15)
				)
				(justify left bottom)
			)
		)
		(property "Author" "Antmicro"
			(at 0 0 0)
			(layer "F.Fab")
			(hide yes)
			(effects
				(font
					(size 1 1)
					(thickness 0.15)
				)
			)
		)
		(property "License" "Apache-2.0"
			(at 0 0 0)
			(layer "F.Fab")
			(hide yes)
			(effects
				(font
					(size 1 1)
					(thickness 0.15)
				)
			)
		)
		(property "MPN" ""
			(at 0 0 0)
			(layer "F.Fab")
			(hide yes)
			(effects
				(font
					(size 1 1)
					(thickness 0.15)
				)
			)
		)
		(property "Manufacturer" ""
			(at 0 0 0)
			(layer "F.Fab")
			(hide yes)
			(effects
				(font
					(size 1 1)
					(thickness 0.15)
				)
			)
		)
		(sheetname "SODIMM")
		(sheetfile "sodim.kicad_sch")
		(attr exclude_from_pos_files)
		(pad "186" smd rect
			(at 49.175 -1.375 180)
			(size 0.35 2.35)
			(layers "B.Cu" "B.Mask")
			(net 14 "GND")
			(pinfunction "VSS")
			(pintype "passive")
		)
		(pad "187" smd rect
			(at 49.425 -1.375)
			(size 0.35 2.35)
			(layers "F.Cu" "F.Mask")
			(net 223 "/LPDDR5/LPDDR5_B.DMI1")
			(pinfunction "DM0_B_n")
			(pintype "passive")
		)
		(pad "188" smd rect
			(at 49.675 -1.375 180)
			(size 0.35 2.35)
			(layers "B.Cu" "B.Mask")
			(net 210 "/LPDDR5/LPDDR5_B.RDQS1_N")
			(pinfunction "DQS0_B_C")
			(pintype "passive")
		)
		(pad "189" smd rect
			(at 49.925 -1.375)
			(size 0.35 2.35)
			(layers "F.Cu" "F.Mask")
			(net 14 "GND")
			(pinfunction "VSS")
			(pintype "passive")
		)
		(pad "190" smd rect
			(at 50.175 -1.375 180)
			(size 0.35 2.35)
			(layers "B.Cu" "B.Mask")
			(net 211 "/LPDDR5/LPDDR5_B.RDQS1_P")
			(pinfunction "DQS0_B_t")
			(pintype "passive")
		)
		(pad "191" smd rect
			(at 50.425 -1.375)
			(size 0.35 2.35)
			(layers "F.Cu" "F.Mask")
			(net 216 "/LPDDR5/LPDDR5_B.DQ15")
			(pinfunction "DQ4_B")
			(pintype "passive")
		)
		(pad "192" smd rect
			(at 50.675 -1.375 180)
			(size 0.35 2.35)
			(layers "B.Cu" "B.Mask")
			(net 14 "GND")
			(pinfunction "VSS")
			(pintype "passive")
		)
		(pad "193" smd rect
			(at 50.925 -1.375)
			(size 0.35 2.35)
			(layers "F.Cu" "F.Mask")
			(net 14 "GND")
			(pinfunction "VSS")
			(pintype "passive")
		)
		(pad "194" smd rect
			(at 51.175 -1.375 180)
			(size 0.35 2.35)
			(layers "B.Cu" "B.Mask")
			(net 215 "/LPDDR5/LPDDR5_B.DQ14")
			(pinfunction "DQ5_B")
			(pintype "passive")
		)
		(pad "195" smd rect
			(at 51.425 -1.375)
			(size 0.35 2.35)
			(layers "F.Cu" "F.Mask")
			(net 213 "/LPDDR5/LPDDR5_B.DQ12")
			(pinfunction "DQ6_B")
			(pintype "passive")
		)
		(pad "196" smd rect
			(at 51.675 -1.375 180)
			(size 0.35 2.35)
			(layers "B.Cu" "B.Mask")
			(net 14 "GND")
			(pinfunction "VSS")
			(pintype "passive")
		)
		(pad "197" smd rect
			(at 51.925 -1.375)
			(size 0.35 2.35)
			(layers "F.Cu" "F.Mask")
			(net 14 "GND")
			(pinfunction "VSS")
			(pintype "passive")
		)
		(pad "198" smd rect
			(at 52.175 -1.375 180)
			(size 0.35 2.35)
			(layers "B.Cu" "B.Mask")
			(net 214 "/LPDDR5/LPDDR5_B.DQ13")
			(pinfunction "DQ7_B")
			(pintype "passive")
		)
		(pad "199" smd rect
			(at 52.425 -1.375)
			(size 0.35 2.35)
			(layers "F.Cu" "F.Mask")
			(net 143 "/SODIMM/LPDDR5_IN_B.DQ8")
			(pinfunction "DQ8_B")
			(pintype "passive")
		)
		(pad "200" smd rect
			(at 52.675 -1.375 180)
			(size 0.35 2.35)
			(layers "B.Cu" "B.Mask")
			(net 14 "GND")
			(pinfunction "VSS")
			(pintype "passive")
		)
		(pad "201" smd rect
			(at 52.925 -1.375)
			(size 0.35 2.35)
			(layers "F.Cu" "F.Mask")
			(net 14 "GND")
			(pinfunction "VSS")
			(pintype "passive")
		)
		(pad "202" smd rect
			(at 53.175 -1.375 180)
			(size 0.35 2.35)
			(layers "B.Cu" "B.Mask")
			(net 141 "/SODIMM/LPDDR5_IN_B.DQ10")
			(pinfunction "DQ9_B")
			(pintype "passive")
		)
		(pad "203" smd rect
			(at 53.425 -1.375)
			(size 0.35 2.35)
			(layers "F.Cu" "F.Mask")
			(net 142 "/SODIMM/LPDDR5_IN_B.DQ9")
			(pinfunction "DQ10_B")
			(pintype "passive")
		)
		(pad "204" smd rect
			(at 53.675 -1.375 180)
			(size 0.35 2.35)
			(layers "B.Cu" "B.Mask")
			(net 14 "GND")
			(pinfunction "VSS")
			(pintype "passive")
		)
		(pad "205" smd rect
			(at 53.925 -1.375)
			(size 0.35 2.35)
			(layers "F.Cu" "F.Mask")
			(net 14 "GND")
			(pinfunction "VSS")
			(pintype "passive")
		)
		(pad "206" smd rect
			(at 54.175 -1.375 180)
			(size 0.35 2.35)
			(layers "B.Cu" "B.Mask")
			(net 140 "/SODIMM/LPDDR5_IN_B.DQ11")
			(pinfunction "DQ11_B")
			(pintype "passive")
		)
		(pad "207" smd rect
			(at 54.425 -1.375)
			(size 0.35 2.35)
			(layers "F.Cu" "F.Mask")
			(net 138 "/SODIMM/LPDDR5_IN_B.WCK1_N")
			(pinfunction "DQS1_B_C")
			(pintype "passive")
		)
		(pad "208" smd rect
			(at 54.675 -1.375 180)
			(size 0.35 2.35)
			(layers "B.Cu" "B.Mask")
			(net 14 "GND")
			(pinfunction "VSS")
			(pintype "passive")
		)
		(pad "209" smd rect
			(at 54.925 -1.375)
			(size 0.35 2.35)
			(layers "F.Cu" "F.Mask")
			(net 137 "/SODIMM/LPDDR5_IN_B.WCK1_P")
			(pinfunction "DQS1_B_t")
			(pintype "passive")
		)
		(pad "210" smd rect
			(at 55.175 -1.375 180)
			(size 0.35 2.35)
			(layers "B.Cu" "B.Mask")
			(net 121 "/SODIMM/LPDDR5_IN_B.DMI1")
			(pinfunction "DM1_B_n")
			(pintype "passive")
		)
		(pad "211" smd rect
			(at 55.425 -1.375)
			(size 0.35 2.35)
			(layers "F.Cu" "F.Mask")
			(net 14 "GND")
			(pinfunction "VSS")
			(pintype "passive")
		)
		(pad "212" smd rect
			(at 55.675 -1.375 180)
			(size 0.35 2.35)
			(layers "B.Cu" "B.Mask")
			(net 14 "GND")
			(pinfunction "VSS")
			(pintype "passive")
		)
		(pad "213" smd rect
			(at 55.925 -1.375)
			(size 0.35 2.35)
			(layers "F.Cu" "F.Mask")
			(net 133 "/SODIMM/LPDDR5_IN_B.DQ15")
			(pinfunction "DQ12_B")
			(pintype "passive")
		)
		(pad "214" smd rect
			(at 56.175 -1.375 180)
			(size 0.35 2.35)
			(layers "B.Cu" "B.Mask")
			(net 134 "/SODIMM/LPDDR5_IN_B.DQ14")
			(pinfunction "DQ13_B")
			(pintype "passive")
		)
		(pad "215" smd rect
			(at 56.425 -1.375)
			(size 0.35 2.35)
			(layers "F.Cu" "F.Mask")
			(net 14 "GND")
			(pinfunction "VSS")
			(pintype "passive")
		)
		(pad "216" smd rect
			(at 56.675 -1.375 180)
			(size 0.35 2.35)
			(layers "B.Cu" "B.Mask")
			(net 14 "GND")
			(pinfunction "VSS")
			(pintype "passive")
		)
		(pad "217" smd rect
			(at 56.925 -1.375)
			(size 0.35 2.35)
			(layers "F.Cu" "F.Mask")
			(net 136 "/SODIMM/LPDDR5_IN_B.DQ12")
			(pinfunction "DQ14_B")
			(pintype "passive")
		)
		(pad "218" smd rect
			(at 57.175 -1.375 180)
			(size 0.35 2.35)
			(layers "B.Cu" "B.Mask")
			(net 135 "/SODIMM/LPDDR5_IN_B.DQ13")
			(pinfunction "DQ15_B")
			(pintype "passive")
		)
		(pad "219" smd rect
			(at 57.425 -1.375)
			(size 0.35 2.35)
			(layers "F.Cu" "F.Mask")
			(net 14 "GND")
			(pinfunction "VSS")
			(pintype "passive")
		)
		(pad "220" smd rect
			(at 57.675 -1.375 180)
			(size 0.35 2.35)
			(layers "B.Cu" "B.Mask")
			(net 14 "GND")
			(pinfunction "VSS")
			(pintype "passive")
		)
		(pad "221" smd rect
			(at 57.925 -1.375)
			(size 0.35 2.35)
			(layers "F.Cu" "F.Mask")
			(net 219 "/LPDDR5/LPDDR5_B.DQ5")
			(pinfunction "DQ16_B")
			(pintype "passive")
		)
		(pad "222" smd rect
			(at 58.175 -1.375 180)
			(size 0.35 2.35)
			(layers "B.Cu" "B.Mask")
			(net 220 "/LPDDR5/LPDDR5_B.DQ4")
			(pinfunction "DQ17_B")
			(pintype "passive")
		)
		(pad "223" smd rect
			(at 58.425 -1.375)
			(size 0.35 2.35)
			(layers "F.Cu" "F.Mask")
			(net 14 "GND")
			(pinfunction "VSS")
			(pintype "passive")
		)
		(pad "224" smd rect
			(at 58.675 -1.375 180)
			(size 0.35 2.35)
			(layers "B.Cu" "B.Mask")
			(net 14 "GND")
			(pinfunction "VSS")
			(pintype "passive")
		)
		(pad "225" smd rect
			(at 58.925 -1.375)
			(size 0.35 2.35)
			(layers "F.Cu" "F.Mask")
			(net 218 "/LPDDR5/LPDDR5_B.DQ6")
			(pinfunction "DQ18_B")
			(pintype "passive")
		)
		(pad "226" smd rect
			(at 59.175 -1.375 180)
			(size 0.35 2.35)
			(layers "B.Cu" "B.Mask")
			(net 217 "/LPDDR5/LPDDR5_B.DQ7")
			(pinfunction "DQ19_B")
			(pintype "passive")
		)
		(pad "227" smd rect
			(at 59.425 -1.375)
			(size 0.35 2.35)
			(layers "F.Cu" "F.Mask")
			(net 14 "GND")
			(pinfunction "VSS")
			(pintype "passive")
		)
		(pad "228" smd rect
			(at 59.675 -1.375 180)
			(size 0.35 2.35)
			(layers "B.Cu" "B.Mask")
			(net 14 "GND")
			(pinfunction "VSS")
			(pintype "passive")
		)
		(pad "229" smd rect
			(at 59.925 -1.375)
			(size 0.35 2.35)
			(layers "F.Cu" "F.Mask")
			(net 212 "/LPDDR5/LPDDR5_B.DMI0")
			(pinfunction "DM2_B_n")
			(pintype "passive")
		)
		(pad "230" smd rect
			(at 60.175 -1.375 180)
			(size 0.35 2.35)
			(layers "B.Cu" "B.Mask")
			(net 221 "/LPDDR5/LPDDR5_B.RDQS0_N")
			(pinfunction "DQS2_B_C")
			(pintype "passive")
		)
		(pad "231" smd rect
			(at 60.425 -1.375)
			(size 0.35 2.35)
			(layers "F.Cu" "F.Mask")
			(net 14 "GND")
			(pinfunction "VSS")
			(pintype "passive")
		)
		(pad "232" smd rect
			(at 60.675 -1.375 180)
			(size 0.35 2.35)
			(layers "B.Cu" "B.Mask")
			(net 222 "/LPDDR5/LPDDR5_B.RDQS0_P")
			(pinfunction "DQS2_B_t")
			(pintype "passive")
		)
		(pad "233" smd rect
			(at 60.925 -1.375)
			(size 0.35 2.35)
			(layers "F.Cu" "F.Mask")
			(net 224 "/LPDDR5/LPDDR5_B.DQ3")
			(pinfunction "DQ20_B")
			(pintype "passive")
		)
		(pad "234" smd rect
			(at 61.175 -1.375 180)
			(size 0.35 2.35)
			(layers "B.Cu" "B.Mask")
			(net 14 "GND")
			(pinfunction "VSS")
			(pintype "passive")
		)
		(pad "235" smd rect
			(at 61.425 -1.375)
			(size 0.35 2.35)
			(layers "F.Cu" "F.Mask")
			(net 14 "GND")
			(pinfunction "VSS")
			(pintype "passive")
		)
		(pad "236" smd rect
			(at 61.675 -1.375 180)
			(size 0.35 2.35)
			(layers "B.Cu" "B.Mask")
			(net 226 "/LPDDR5/LPDDR5_B.DQ1")
			(pinfunction "DQ21_B")
			(pintype "passive")
		)
		(pad "237" smd rect
			(at 61.925 -1.375)
			(size 0.35 2.35)
			(layers "F.Cu" "F.Mask")
			(net 225 "/LPDDR5/LPDDR5_B.DQ2")
			(pinfunction "DQ22_B")
			(pintype "passive")
		)
		(pad "238" smd rect
			(at 62.175 -1.375 180)
			(size 0.35 2.35)
			(layers "B.Cu" "B.Mask")
			(net 14 "GND")
			(pinfunction "VSS")
			(pintype "passive")
		)
		(pad "239" smd rect
			(at 62.425 -1.375)
			(size 0.35 2.35)
			(layers "F.Cu" "F.Mask")
			(net 14 "GND")
			(pinfunction "VSS")
			(pintype "passive")
		)
		(pad "240" smd rect
			(at 62.675 -1.375 180)
			(size 0.35 2.35)
			(layers "B.Cu" "B.Mask")
			(net 227 "/LPDDR5/LPDDR5_B.DQ0")
			(pinfunction "DQ23_B")
			(pintype "passive")
		)
		(pad "241" smd rect
			(at 62.925 -1.375)
			(size 0.35 2.35)
			(layers "F.Cu" "F.Mask")
			(net 130 "/SODIMM/LPDDR5_IN_B.DQ5")
			(pinfunction "DQ24_B")
			(pintype "passive")
		)
		(pad "242" smd rect
			(at 63.175 -1.375 180)
			(size 0.35 2.35)
			(layers "B.Cu" "B.Mask")
			(net 14 "GND")
			(pinfunction "VSS")
			(pintype "passive")
		)
		(pad "243" smd rect
			(at 63.425 -1.375)
			(size 0.35 2.35)
			(layers "F.Cu" "F.Mask")
			(net 14 "GND")
			(pinfunction "VSS")
			(pintype "passive")
		)
		(pad "244" smd rect
			(at 63.675 -1.375 180)
			(size 0.35 2.35)
			(layers "B.Cu" "B.Mask")
			(net 129 "/SODIMM/LPDDR5_IN_B.DQ4")
			(pinfunction "DQ25_B")
			(pintype "passive")
		)
		(pad "245" smd rect
			(at 63.925 -1.375)
			(size 0.35 2.35)
			(layers "F.Cu" "F.Mask")
			(net 131 "/SODIMM/LPDDR5_IN_B.DQ6")
			(pinfunction "DQ26_B")
			(pintype "passive")
		)
		(pad "246" smd rect
			(at 64.175 -1.375 180)
			(size 0.35 2.35)
			(layers "B.Cu" "B.Mask")
			(net 14 "GND")
			(pinfunction "VSS")
			(pintype "passive")
		)
		(pad "247" smd rect
			(at 64.425 -1.375)
			(size 0.35 2.35)
			(layers "F.Cu" "F.Mask")
			(net 14 "GND")
			(pinfunction "VSS")
			(pintype "passive")
		)
		(pad "248" smd rect
			(at 64.675 -1.375 180)
			(size 0.35 2.35)
			(layers "B.Cu" "B.Mask")
			(net 132 "/SODIMM/LPDDR5_IN_B.DQ7")
			(pinfunction "DQ27_B")
			(pintype "passive")
		)
		(pad "249" smd rect
			(at 64.925 -1.375)
			(size 0.35 2.35)
			(layers "F.Cu" "F.Mask")
			(net 127 "/SODIMM/LPDDR5_IN_B.WCK0_N")
			(pinfunction "DQS3_B_c")
			(pintype "passive")
		)
		(pad "250" smd rect
			(at 65.175 -1.375 180)
			(size 0.35 2.35)
			(layers "B.Cu" "B.Mask")
			(net 14 "GND")
			(pinfunction "VSS")
			(pintype "passive")
		)
		(pad "251" smd rect
			(at 65.425 -1.375)
			(size 0.35 2.35)
			(layers "F.Cu" "F.Mask")
			(net 126 "/SODIMM/LPDDR5_IN_B.WCK0_P")
			(pinfunction "DQS3_B_t")
			(pintype "passive")
		)
		(pad "252" smd rect
			(at 65.675 -1.375 180)
			(size 0.35 2.35)
			(layers "B.Cu" "B.Mask")
			(net 120 "/SODIMM/LPDDR5_IN_B.DMI0")
			(pinfunction "DM3_B_n")
			(pintype "passive")
		)
		(pad "253" smd rect
			(at 65.925 -1.375)
			(size 0.35 2.35)
			(layers "F.Cu" "F.Mask")
			(net 14 "GND")
			(pinfunction "VSS")
			(pintype "passive")
		)
		(pad "254" smd rect
			(at 66.175 -1.375 180)
			(size 0.35 2.35)
			(layers "B.Cu" "B.Mask")
			(net 14 "GND")
			(pinfunction "VSS")
			(pintype "passive")
		)
		(pad "255" smd rect
			(at 66.425 -1.375)
			(size 0.35 2.35)
			(layers "F.Cu" "F.Mask")
			(net 125 "/SODIMM/LPDDR5_IN_B.DQ3")
			(pinfunction "DQ28_B")
			(pintype "passive")
		)
		(pad "256" smd rect
			(at 66.675 -1.375 180)
			(size 0.35 2.35)
			(layers "B.Cu" "B.Mask")
			(net 123 "/SODIMM/LPDDR5_IN_B.DQ1")
			(pinfunction "DQ29_B")
			(pintype "passive")
		)
		(pad "257" smd rect
			(at 66.925 -1.375)
			(size 0.35 2.35)
			(layers "F.Cu" "F.Mask")
			(net 14 "GND")
			(pinfunction "VSS")
			(pintype "passive")
		)
		(pad "258" smd rect
			(at 67.175 -1.375 180)
			(size 0.35 2.35)
			(layers "B.Cu" "B.Mask")
			(net 14 "GND")
			(pinfunction "VSS")
			(pintype "passive")
		)
		(pad "259" smd rect
			(at 67.425 -1.375)
			(size 0.35 2.35)
			(layers "F.Cu" "F.Mask")
			(net 124 "/SODIMM/LPDDR5_IN_B.DQ2")
			(pinfunction "DQ30_B")
			(pintype "passive")
		)
		(pad "260" smd rect
			(at 67.675 -1.375 180)
			(size 0.35 2.35)
			(layers "B.Cu" "B.Mask")
			(net 122 "/SODIMM/LPDDR5_IN_B.DQ0")
			(pinfunction "DQ31_B")
			(pintype "passive")
		)
		(pad "261" smd rect
			(at 67.925 -1.375)
			(size 0.35 2.35)
			(layers "F.Cu" "F.Mask")
			(net 14 "GND")
			(pinfunction "VSS")
			(pintype "passive")
		)
		(pad "262" smd rect
			(at 68.175 -1.375 180)
			(size 0.35 2.35)
			(layers "B.Cu" "B.Mask")
			(net 14 "GND")
			(pinfunction "VSS")
			(pintype "passive")
		)
	)
)
